# S9S_MB_2U (Grand Teton) — schematic netlist excerpt (pin names and nets, part order shuffled) for the footprints in the layout excerpt that follows; sources: Cadence DE-HDL packaged netlist, KiCad conversion of 03242023_DA0F0TMBIJ0_F0T_Motherboard_J_brd_V01_OCP.brd

R4629  Q_RES  0 5% CHIP  pkg 0402LF  page 248 : A = JTAG_BMC_TCK ; B = JTAG_BMC_TCK_R
PR200  Q_RES  2.2 1% CHIP  pkg 0402LF  page 297 : A = PVCCFA_EHV_CPU1_PVCC ; B = PVCCD_HV_CPU1_VDD1

(kicad_pcb
	(version 20260206)
	(generator "pcbnew")
	(generator_version "10.0")
	(general
		(thickness 1.6)
		(legacy_teardrops no)
	)
	(paper "A4")
	(title_block
		(title "03242023_DA0F0TMBIJ0_F0T_Motherboard_J_brd_V01_OCP.brd")
		(comment 1 "Grand Teton / footprints 4999-5000 of 6105")
	)
	(layers
		(0 "F.Cu" signal "TOP")
		(4 "In1.Cu" signal "GND")
		(6 "In2.Cu" signal "IN1")
		(8 "In3.Cu" signal "GND1")
		(10 "In4.Cu" signal "IN2")
		(12 "In5.Cu" signal "GND2")
		(14 "In6.Cu" signal "IN3")
		(16 "In7.Cu" signal "GND3")
		(18 "In8.Cu" signal "VCC")
		(20 "In9.Cu" signal "VCC1")
		(22 "In10.Cu" signal "GND4")
		(24 "In11.Cu" signal "IN4")
		(26 "In12.Cu" signal "GND5")
		(28 "In13.Cu" signal "IN5")
		(30 "In14.Cu" signal "GND6")
		(32 "In15.Cu" signal "IN6")
		(34 "In16.Cu" signal "GND7")
		(2 "B.Cu" signal "BOTTOM")
		(9 "F.Adhes" user "F.Adhesive")
		(11 "B.Adhes" user "B.Adhesive")
		(13 "F.Paste" user "Package Geometry/Pastemask Top")
		(15 "B.Paste" user "Package Geometry/Pastemask Bottom")
		(5 "F.SilkS" user "Ref Des/Silkscreen Top")
		(7 "B.SilkS" user "Ref Des/Silkscreen Bottom")
		(1 "F.Mask" user "Board Geometry/Soldermask Top")
		(3 "B.Mask" user "Board Geometry/Soldermask Bottom")
		(17 "Dwgs.User" user "User.Drawings")
		(19 "Cmts.User" user "User.Comments")
		(21 "Eco1.User" user "User.Eco1")
		(23 "Eco2.User" user "User.Eco2")
		(25 "Edge.Cuts" user "Board Geometry/Outline")
		(27 "Margin" user)
		(31 "F.CrtYd" user "Package Geometry/Place Bound Top")
		(29 "B.CrtYd" user "Package Geometry/Place Bound Bottom")
		(35 "F.Fab" user "Ref Des/Assembly Top")
		(33 "B.Fab" user "Ref Des/Assembly Bottom")
	)
	(footprint ""
		(layer "B.Cu")
		(at 149.8854 -14.823948 -90)
		(property "Reference" "R4629"
			(at 0 0 90)
			(layer "B.SilkS")
			(hide yes)
			(effects
				(font
					(size 1.27 1.27)
				)
				(justify mirror)
			)
		)
		(property "Value" ""
			(at 0 0 90)
			(layer "B.Fab")
			(effects
				(font
					(size 1.27 1.27)
				)
				(justify mirror)
			)
		)
		(duplicate_pad_numbers_are_jumpers no)
		(fp_line
			(start -0.7874 0.4064)
			(end 0.7874 0.4064)
			(stroke
				(width 0.1524)
				(type default)
			)
			(layer "B.SilkS")
		)
		(fp_line
			(start 0.7874 0.4064)
			(end 0.7874 -0.4064)
			(stroke
				(width 0.1524)
				(type default)
			)
			(layer "B.SilkS")
		)
		(fp_line
			(start -0.7874 -0.4064)
			(end -0.7874 0.4064)
			(stroke
				(width 0.1524)
				(type default)
			)
			(layer "B.SilkS")
		)
		(fp_line
			(start 0.7874 -0.4064)
			(end -0.7874 -0.4064)
			(stroke
				(width 0.1524)
				(type default)
			)
			(layer "B.SilkS")
		)
		(fp_line
			(start -0.67945 0.3048)
			(end -0.120396 0.3048)
			(stroke
				(width 0.1)
				(type default)
			)
			(layer "B.Fab")
		)
		(fp_line
			(start -0.120396 0.3048)
			(end -0.120396 0.2794)
			(stroke
				(width 0.1)
				(type default)
			)
			(layer "B.Fab")
		)
		(fp_line
			(start 0.12065 0.3048)
			(end 0.67945 0.3048)
			(stroke
				(width 0.1)
				(type default)
			)
			(layer "B.Fab")
		)
		(fp_line
			(start 0.67945 0.3048)
			(end 0.67945 -0.305054)
			(stroke
				(width 0.1)
				(type default)
			)
			(layer "B.Fab")
		)
		(fp_line
			(start -0.120396 0.2794)
			(end 0.12065 0.2794)
			(stroke
				(width 0.1)
				(type default)
			)
			(layer "B.Fab")
		)
		(fp_line
			(start 0.12065 0.2794)
			(end 0.12065 0.3048)
			(stroke
				(width 0.1)
				(type default)
			)
			(layer "B.Fab")
		)
		(fp_line
			(start -0.12065 -0.2794)
			(end -0.12065 -0.3048)
			(stroke
				(width 0.1)
				(type default)
			)
			(layer "B.Fab")
		)
		(fp_line
			(start 0.12065 -0.2794)
			(end -0.12065 -0.2794)
			(stroke
				(width 0.1)
				(type default)
			)
			(layer "B.Fab")
		)
		(fp_line
			(start -0.67945 -0.3048)
			(end -0.67945 0.3048)
			(stroke
				(width 0.1)
				(type default)
			)
			(layer "B.Fab")
		)
		(fp_line
			(start -0.12065 -0.3048)
			(end -0.67945 -0.3048)
			(stroke
				(width 0.1)
				(type default)
			)
			(layer "B.Fab")
		)
		(fp_line
			(start 0.12065 -0.305054)
			(end 0.12065 -0.2794)
			(stroke
				(width 0.1)
				(type default)
			)
			(layer "B.Fab")
		)
		(fp_line
			(start 0.67945 -0.305054)
			(end 0.12065 -0.305054)
			(stroke
				(width 0.1)
				(type default)
			)
			(layer "B.Fab")
		)
		(pad "1" smd circle
			(at 0.40005 0 90)
			(size 0 0)
			(layers "B.Cu" "B.Mask" "B.Paste")
			(net "JTAG_BMC_TCK")
		)
		(pad "2" smd circle
			(at -0.40005 0 90)
			(size 0 0)
			(layers "B.Cu" "B.Mask" "B.Paste")
			(net "JTAG_BMC_TCK_R")
		)
	)
	(footprint ""
		(layer "B.Cu")
		(at 53.912516 -162.717226)
		(property "Reference" "PR200"
			(at 0 0 0)
			(layer "B.SilkS")
			(hide yes)
			(effects
				(font
					(size 1.27 1.27)
				)
				(justify mirror)
			)
		)
		(property "Value" ""
			(at 0 0 0)
			(layer "B.Fab")
			(effects
				(font
					(size 1.27 1.27)
				)
				(justify mirror)
			)
		)
		(duplicate_pad_numbers_are_jumpers no)
		(fp_line
			(start -0.7874 -0.4064)
			(end -0.7874 0.4064)
			(stroke
				(width 0.1524)
				(type default)
			)
			(layer "B.SilkS")
		)
		(fp_line
			(start -0.7874 0.4064)
			(end 0.7874 0.4064)
			(stroke
				(width 0.1524)
				(type default)
			)
			(layer "B.SilkS")
		)
		(fp_line
			(start 0.7874 -0.4064)
			(end -0.7874 -0.4064)
			(stroke
				(width 0.1524)
				(type default)
			)
			(layer "B.SilkS")
		)
		(fp_line
			(start 0.7874 0.4064)
			(end 0.7874 -0.4064)
			(stroke
				(width 0.1524)
				(type default)
			)
			(layer "B.SilkS")
		)
		(fp_line
			(start -0.67945 -0.3048)
			(end -0.67945 0.3048)
			(stroke
				(width 0.1)
				(type default)
			)
			(layer "B.Fab")
		)
		(fp_line
			(start -0.67945 0.3048)
			(end -0.120396 0.3048)
			(stroke
				(width 0.1)
				(type default)
			)
			(layer "B.Fab")
		)
		(fp_line
			(start -0.12065 -0.3048)
			(end -0.67945 -0.3048)
			(stroke
				(width 0.1)
				(type default)
			)
			(layer "B.Fab")
		)
		(fp_line
			(start -0.12065 -0.2794)
			(end -0.12065 -0.3048)
			(stroke
				(width 0.1)
				(type default)
			)
			(layer "B.Fab")
		)
		(fp_line
			(start -0.120396 0.2794)
			(end 0.12065 0.2794)
			(stroke
				(width 0.1)
				(type default)
			)
			(layer "B.Fab")
		)
		(fp_line
			(start -0.120396 0.3048)
			(end -0.120396 0.2794)
			(stroke
				(width 0.1)
				(type default)
			)
			(layer "B.Fab")
		)
		(fp_line
			(start 0.12065 -0.305054)
			(end 0.12065 -0.2794)
			(stroke
				(width 0.1)
				(type default)
			)
			(layer "B.Fab")
		)
		(fp_line
			(start 0.12065 -0.2794)
			(end -0.12065 -0.2794)
			(stroke
				(width 0.1)
				(type default)
			)
			(layer "B.Fab")
		)
		(fp_line
			(start 0.12065 0.2794)
			(end 0.12065 0.3048)
			(stroke
				(width 0.1)
				(type default)
			)
			(layer "B.Fab")
		)
		(fp_line
			(start 0.12065 0.3048)
			(end 0.67945 0.3048)
			(stroke
				(width 0.1)
				(type default)
			)
			(layer "B.Fab")
		)
		(fp_line
			(start 0.67945 -0.305054)
			(end 0.12065 -0.305054)
			(stroke
				(width 0.1)
				(type default)
			)
			(layer "B.Fab")
		)
		(fp_line
			(start 0.67945 0.3048)
			(end 0.67945 -0.305054)
			(stroke
				(width 0.1)
				(type default)
			)
			(layer "B.Fab")
		)
		(pad "1" smd circle
			(at 0.40005 0 180)
			(size 0 0)
			(layers "B.Cu" "B.Mask" "B.Paste")
			(net "PVCCFA_EHV_CPU1_PVCC")
		)
		(pad "2" smd circle
			(at -0.40005 0 180)
			(size 0 0)
			(layers "B.Cu" "B.Mask" "B.Paste")
			(net "PVCCD_HV_CPU1_VDD1")
		)
	)
)
